(kicad_pcb
	(version 20260206)
	(generator "pcbnew")
	(generator_version "10.0")
	(general
		(thickness 1.6)
		(legacy_teardrops no)
	)
	(paper "A4")
	(title_block
		(title "peb — Lightning_PEB_BRD.brd")
		(comment 1 "Lightning (Wiwynn / Facebook NVMe JBOF) / footprint 41 of 2563 (GF8), pads 114-200 of 200")
	)
	(layers
		(0 "F.Cu" signal "TOP")
		(4 "In1.Cu" signal "L2GND")
		(6 "In2.Cu" signal "L3")
		(8 "In3.Cu" signal "L4VCC")
		(10 "In4.Cu" signal "L5VCC")
		(12 "In5.Cu" signal "L6")
		(14 "In6.Cu" signal "L7GND")
		(2 "B.Cu" signal "BOTTOM")
		(9 "F.Adhes" user "F.Adhesive")
		(11 "B.Adhes" user "B.Adhesive")
		(13 "F.Paste" user "Package Geometry/Pastemask Top")
		(15 "B.Paste" user "Package Geometry/Pastemask Bottom")
		(5 "F.SilkS" user "Ref Des/Silkscreen Top")
		(7 "B.SilkS" user "Ref Des/Silkscreen Bottom")
		(1 "F.Mask" user "Board Geometry/Soldermask Top")
		(3 "B.Mask" user "Board Geometry/Soldermask Bottom")
		(17 "Dwgs.User" user "User.Drawings")
		(19 "Cmts.User" user "User.Comments")
		(21 "Eco1.User" user "User.Eco1")
		(23 "Eco2.User" user "User.Eco2")
		(25 "Edge.Cuts" user "Board Geometry/Outline")
		(27 "Margin" user)
		(31 "F.CrtYd" user "Package Geometry/Place Bound Top")
		(29 "B.CrtYd" user "Package Geometry/Place Bound Bottom")
		(35 "F.Fab" user "Ref Des/Assembly Top")
		(33 "B.Fab" user "Ref Des/Assembly Bottom")
	)
	(footprint ""
		(layer "F.Cu")
		(at 75.300078 -226.70008 180)
		(property "Reference" "GF8"
			(at 0 0 180)
			(layer "F.SilkS")
			(hide yes)
			(effects
				(font
					(size 1.27 1.27)
				)
			)
		)
		(property "Value" "GF-200P-8-GP-U1"
			(at -43.1673 -7.6327 180)
			(unlocked yes)
			(layer "F.Fab")
			(hide yes)
			(effects
				(font
					(size 1.016 1.016)
					(thickness 0.1524)
				)
			)
		)
		(property "Device Type" "GF-200P-8-U1"
			(at -43.1673 -9.1567 180)
			(unlocked yes)
			(layer "F.Fab")
			(hide yes)
			(effects
				(font
					(size 1.016 1.016)
					(thickness 0.1524)
				)
			)
		)
		(duplicate_pad_numbers_are_jumpers no)
		(pad "B14" smd rect
			(at -25.999948 -0.7747 180)
			(size 0.5588 2.3114)
			(drill
				(offset 0 -0.381)
			)
			(layers "F.Cu" "F.Mask" "F.Paste")
			(net "GND")
		)
		(pad "B15" smd rect
			(at -25.200102 -0.7747 180)
			(size 0.5588 2.3114)
			(drill
				(offset 0 -0.381)
			)
			(layers "F.Cu" "F.Mask" "F.Paste")
			(net "PCIE_RX_N62")
		)
		(pad "B16" smd rect
			(at -24.400002 -0.7747 180)
			(size 0.5588 2.3114)
			(drill
				(offset 0 -0.381)
			)
			(layers "F.Cu" "F.Mask" "F.Paste")
			(net "PCIE_RX_P62")
		)
		(pad "B17" smd rect
			(at -23.599902 -0.7747 180)
			(size 0.5588 2.3114)
			(drill
				(offset 0 -0.381)
			)
			(layers "F.Cu" "F.Mask" "F.Paste")
			(net "GND")
		)
		(pad "B18" smd rect
			(at -22.800056 -0.7747 180)
			(size 0.5588 2.3114)
			(drill
				(offset 0 -0.381)
			)
			(layers "F.Cu" "F.Mask" "F.Paste")
			(net "GND")
		)
		(pad "B19" smd rect
			(at -21.999956 -0.7747 180)
			(size 0.5588 2.3114)
			(drill
				(offset 0 -0.381)
			)
			(layers "F.Cu" "F.Mask" "F.Paste")
			(net "PCIE_RX_N63")
		)
		(pad "B20" smd rect
			(at -21.20011 -0.7747 180)
			(size 0.5588 2.3114)
			(drill
				(offset 0 -0.381)
			)
			(layers "F.Cu" "F.Mask" "F.Paste")
			(net "PCIE_RX_P63")
		)
		(pad "B21" smd rect
			(at -20.40001 -0.7747 180)
			(size 0.5588 2.3114)
			(drill
				(offset 0 -0.381)
			)
			(layers "F.Cu" "F.Mask" "F.Paste")
			(net "GND")
		)
		(pad "B22" smd rect
			(at -19.59991 -0.7747 180)
			(size 0.5588 2.3114)
			(drill
				(offset 0 -0.381)
			)
			(layers "F.Cu" "F.Mask" "F.Paste")
			(net "SSD_PWREN10_R")
		)
		(pad "B23" smd rect
			(at -18.800064 -0.7747 180)
			(size 0.5588 2.3114)
			(drill
				(offset 0 -0.381)
			)
			(layers "F.Cu" "F.Mask" "F.Paste")
			(net "SSD_ATNLED#10_R")
		)
		(pad "B24" smd rect
			(at -17.999964 -0.7747 180)
			(size 0.5588 2.3114)
			(drill
				(offset 0 -0.381)
			)
			(layers "F.Cu" "F.Mask" "F.Paste")
			(net "SSD_PRSNT#10_R")
		)
		(pad "B25" smd rect
			(at -17.200118 -0.7747 180)
			(size 0.5588 2.3114)
			(drill
				(offset 0 -0.381)
			)
			(layers "F.Cu" "F.Mask" "F.Paste")
			(net "GND")
		)
		(pad "B26" smd rect
			(at -16.400018 -0.7747 180)
			(size 0.5588 2.3114)
			(drill
				(offset 0 -0.381)
			)
			(layers "F.Cu" "F.Mask" "F.Paste")
			(net "PCIE_RX_N64")
		)
		(pad "B27" smd rect
			(at -15.599918 -0.7747 180)
			(size 0.5588 2.3114)
			(drill
				(offset 0 -0.381)
			)
			(layers "F.Cu" "F.Mask" "F.Paste")
			(net "PCIE_RX_P64")
		)
		(pad "B28" smd rect
			(at -14.800072 -0.7747 180)
			(size 0.5588 2.3114)
			(drill
				(offset 0 -0.381)
			)
			(layers "F.Cu" "F.Mask" "F.Paste")
			(net "GND")
		)
		(pad "B29" smd rect
			(at -13.999972 -0.7747 180)
			(size 0.5588 2.3114)
			(drill
				(offset 0 -0.381)
			)
			(layers "F.Cu" "F.Mask" "F.Paste")
			(net "GND")
		)
		(pad "B30" smd rect
			(at -13.200126 -0.7747 180)
			(size 0.5588 2.3114)
			(drill
				(offset 0 -0.381)
			)
			(layers "F.Cu" "F.Mask" "F.Paste")
			(net "PCIE_RX_N65")
		)
		(pad "B31" smd rect
			(at -12.400026 -0.7747 180)
			(size 0.5588 2.3114)
			(drill
				(offset 0 -0.381)
			)
			(layers "F.Cu" "F.Mask" "F.Paste")
			(net "PCIE_RX_P65")
		)
		(pad "B32" smd rect
			(at -11.599926 -0.7747 180)
			(size 0.5588 2.3114)
			(drill
				(offset 0 -0.381)
			)
			(layers "F.Cu" "F.Mask" "F.Paste")
			(net "GND")
		)
		(pad "B33" smd rect
			(at -10.80008 -0.7747 180)
			(size 0.5588 2.3114)
			(drill
				(offset 0 -0.381)
			)
			(layers "F.Cu" "F.Mask" "F.Paste")
			(net "GND")
		)
		(pad "B34" smd rect
			(at -9.99998 -0.7747 180)
			(size 0.5588 2.3114)
			(drill
				(offset 0 -0.381)
			)
			(layers "F.Cu" "F.Mask" "F.Paste")
			(net "PCIE_RX_N66")
		)
		(pad "B35" smd rect
			(at -9.19988 -0.7747 180)
			(size 0.5588 2.3114)
			(drill
				(offset 0 -0.381)
			)
			(layers "F.Cu" "F.Mask" "F.Paste")
			(net "PCIE_RX_P66")
		)
		(pad "B36" smd rect
			(at -8.400034 -0.7747 180)
			(size 0.5588 2.3114)
			(drill
				(offset 0 -0.381)
			)
			(layers "F.Cu" "F.Mask" "F.Paste")
			(net "GND")
		)
		(pad "B37" smd rect
			(at -7.599934 -0.7747 180)
			(size 0.5588 2.3114)
			(drill
				(offset 0 -0.381)
			)
			(layers "F.Cu" "F.Mask" "F.Paste")
			(net "GND")
		)
		(pad "B38" smd rect
			(at -6.800088 -0.7747 180)
			(size 0.5588 2.3114)
			(drill
				(offset 0 -0.381)
			)
			(layers "F.Cu" "F.Mask" "F.Paste")
			(net "PCIE_RX_N67")
		)
		(pad "B39" smd rect
			(at -5.999988 -0.7747 180)
			(size 0.5588 2.3114)
			(drill
				(offset 0 -0.381)
			)
			(layers "F.Cu" "F.Mask" "F.Paste")
			(net "PCIE_RX_P67")
		)
		(pad "B40" smd rect
			(at -5.199888 -0.7747 180)
			(size 0.5588 2.3114)
			(drill
				(offset 0 -0.381)
			)
			(layers "F.Cu" "F.Mask" "F.Paste")
			(net "GND")
		)
		(pad "B41" smd rect
			(at -4.400042 -0.7747 180)
			(size 0.5588 2.3114)
			(drill
				(offset 0 -0.381)
			)
			(layers "F.Cu" "F.Mask" "F.Paste")
			(net "GND")
		)
		(pad "B42" smd rect
			(at -3.599942 -0.7747 180)
			(size 0.5588 2.3114)
			(drill
				(offset 0 -0.381)
			)
			(layers "F.Cu" "F.Mask" "F.Paste")
			(net "PCIE_RX_N68")
		)
		(pad "B43" smd rect
			(at -2.800096 -0.7747 180)
			(size 0.5588 2.3114)
			(drill
				(offset 0 -0.381)
			)
			(layers "F.Cu" "F.Mask" "F.Paste")
			(net "PCIE_RX_P68")
		)
		(pad "B44" smd rect
			(at -1.999996 -0.7747 180)
			(size 0.5588 2.3114)
			(drill
				(offset 0 -0.381)
			)
			(layers "F.Cu" "F.Mask" "F.Paste")
			(net "GND")
		)
		(pad "B45" smd rect
			(at 1.999996 -0.7747 180)
			(size 0.5588 2.3114)
			(drill
				(offset 0 -0.381)
			)
			(layers "F.Cu" "F.Mask" "F.Paste")
			(net "GND")
		)
		(pad "B46" smd rect
			(at 2.800096 -0.7747 180)
			(size 0.5588 2.3114)
			(drill
				(offset 0 -0.381)
			)
			(layers "F.Cu" "F.Mask" "F.Paste")
			(net "PCIE_RX_N69")
		)
		(pad "B47" smd rect
			(at 3.599942 -0.7747 180)
			(size 0.5588 2.3114)
			(drill
				(offset 0 -0.381)
			)
			(layers "F.Cu" "F.Mask" "F.Paste")
			(net "PCIE_RX_P69")
		)
		(pad "B48" smd rect
			(at 4.400042 -0.7747 180)
			(size 0.5588 2.3114)
			(drill
				(offset 0 -0.381)
			)
			(layers "F.Cu" "F.Mask" "F.Paste")
			(net "GND")
		)
		(pad "B49" smd rect
			(at 5.199888 -0.7747 180)
			(size 0.5588 2.3114)
			(drill
				(offset 0 -0.381)
			)
			(layers "F.Cu" "F.Mask" "F.Paste")
			(net "GND")
		)
		(pad "B50" smd rect
			(at 5.999988 -0.7747 180)
			(size 0.5588 2.3114)
			(drill
				(offset 0 -0.381)
			)
			(layers "F.Cu" "F.Mask" "F.Paste")
			(net "PCIE_RX_N70")
		)
		(pad "B51" smd rect
			(at 6.800088 -0.7747 180)
			(size 0.5588 2.3114)
			(drill
				(offset 0 -0.381)
			)
			(layers "F.Cu" "F.Mask" "F.Paste")
			(net "PCIE_RX_P70")
		)
		(pad "B52" smd rect
			(at 7.599934 -0.7747 180)
			(size 0.5588 2.3114)
			(drill
				(offset 0 -0.381)
			)
			(layers "F.Cu" "F.Mask" "F.Paste")
			(net "GND")
		)
		(pad "B53" smd rect
			(at 8.400034 -0.7747 180)
			(size 0.5588 2.3114)
			(drill
				(offset 0 -0.381)
			)
			(layers "F.Cu" "F.Mask" "F.Paste")
			(net "GND")
		)
		(pad "B54" smd rect
			(at 9.19988 -0.7747 180)
			(size 0.5588 2.3114)
			(drill
				(offset 0 -0.381)
			)
			(layers "F.Cu" "F.Mask" "F.Paste")
			(net "PCIE_RX_N71")
		)
		(pad "B55" smd rect
			(at 9.99998 -0.7747 180)
			(size 0.5588 2.3114)
			(drill
				(offset 0 -0.381)
			)
			(layers "F.Cu" "F.Mask" "F.Paste")
			(net "PCIE_RX_P71")
		)
		(pad "B56" smd rect
			(at 10.80008 -0.7747 180)
			(size 0.5588 2.3114)
			(drill
				(offset 0 -0.381)
			)
			(layers "F.Cu" "F.Mask" "F.Paste")
			(net "GND")
		)
		(pad "B57" smd rect
			(at 11.599926 -0.7747 180)
			(size 0.5588 2.3114)
			(drill
				(offset 0 -0.381)
			)
			(layers "F.Cu" "F.Mask" "F.Paste")
			(net "SSD_PRSNT#5_R")
		)
		(pad "B58" smd rect
			(at 12.400026 -0.7747 180)
			(size 0.5588 2.3114)
			(drill
				(offset 0 -0.381)
			)
			(layers "F.Cu" "F.Mask" "F.Paste")
			(net "SSD_ATNLED#5_R")
		)
		(pad "B59" smd rect
			(at 13.200126 -0.7747 180)
			(size 0.5588 2.3114)
			(drill
				(offset 0 -0.381)
			)
			(layers "F.Cu" "F.Mask" "F.Paste")
			(net "SSD_PWREN5_R")
		)
		(pad "B60" smd rect
			(at 13.999972 -0.7747 180)
			(size 0.5588 2.3114)
			(drill
				(offset 0 -0.381)
			)
			(layers "F.Cu" "F.Mask" "F.Paste")
			(net "GND")
		)
		(pad "B61" smd rect
			(at 14.800072 -0.7747 180)
			(size 0.5588 2.3114)
			(drill
				(offset 0 -0.381)
			)
			(layers "F.Cu" "F.Mask" "F.Paste")
			(net "PCIE_RX_N72")
		)
		(pad "B62" smd rect
			(at 15.599918 -0.7747 180)
			(size 0.5588 2.3114)
			(drill
				(offset 0 -0.381)
			)
			(layers "F.Cu" "F.Mask" "F.Paste")
			(net "PCIE_RX_P72")
		)
		(pad "B63" smd rect
			(at 16.400018 -0.7747 180)
			(size 0.5588 2.3114)
			(drill
				(offset 0 -0.381)
			)
			(layers "F.Cu" "F.Mask" "F.Paste")
			(net "GND")
		)
		(pad "B64" smd rect
			(at 17.200118 -0.7747 180)
			(size 0.5588 2.3114)
			(drill
				(offset 0 -0.381)
			)
			(layers "F.Cu" "F.Mask" "F.Paste")
			(net "GND")
		)
		(pad "B65" smd rect
			(at 17.999964 -0.7747 180)
			(size 0.5588 2.3114)
			(drill
				(offset 0 -0.381)
			)
			(layers "F.Cu" "F.Mask" "F.Paste")
			(net "PCIE_RX_N73")
		)
		(pad "B66" smd rect
			(at 18.800064 -0.7747 180)
			(size 0.5588 2.3114)
			(drill
				(offset 0 -0.381)
			)
			(layers "F.Cu" "F.Mask" "F.Paste")
			(net "PCIE_RX_P73")
		)
		(pad "B67" smd rect
			(at 19.59991 -0.7747 180)
			(size 0.5588 2.3114)
			(drill
				(offset 0 -0.381)
			)
			(layers "F.Cu" "F.Mask" "F.Paste")
			(net "GND")
		)
		(pad "B68" smd rect
			(at 20.40001 -0.7747 180)
			(size 0.5588 2.3114)
			(drill
				(offset 0 -0.381)
			)
			(layers "F.Cu" "F.Mask" "F.Paste")
			(net "GND")
		)
		(pad "B69" smd rect
			(at 21.20011 -0.7747 180)
			(size 0.5588 2.3114)
			(drill
				(offset 0 -0.381)
			)
			(layers "F.Cu" "F.Mask" "F.Paste")
			(net "PCIE_RX_N74")
		)
		(pad "B70" smd rect
			(at 21.999956 -0.7747 180)
			(size 0.5588 2.3114)
			(drill
				(offset 0 -0.381)
			)
			(layers "F.Cu" "F.Mask" "F.Paste")
			(net "PCIE_RX_P74")
		)
		(pad "B71" smd rect
			(at 22.800056 -0.7747 180)
			(size 0.5588 2.3114)
			(drill
				(offset 0 -0.381)
			)
			(layers "F.Cu" "F.Mask" "F.Paste")
			(net "GND")
		)
		(pad "B72" smd rect
			(at 23.599902 -0.7747 180)
			(size 0.5588 2.3114)
			(drill
				(offset 0 -0.381)
			)
			(layers "F.Cu" "F.Mask" "F.Paste")
			(net "GND")
		)
		(pad "B73" smd rect
			(at 24.400002 -0.7747 180)
			(size 0.5588 2.3114)
			(drill
				(offset 0 -0.381)
			)
			(layers "F.Cu" "F.Mask" "F.Paste")
			(net "PCIE_RX_N75")
		)
		(pad "B74" smd rect
			(at 25.200102 -0.7747 180)
			(size 0.5588 2.3114)
			(drill
				(offset 0 -0.381)
			)
			(layers "F.Cu" "F.Mask" "F.Paste")
			(net "PCIE_RX_P75")
		)
		(pad "B75" smd rect
			(at 25.999948 -0.7747 180)
			(size 0.5588 2.3114)
			(drill
				(offset 0 -0.381)
			)
			(layers "F.Cu" "F.Mask" "F.Paste")
			(net "GND")
		)
		(pad "B76" smd rect
			(at 26.800048 -0.7747 180)
			(size 0.5588 2.3114)
			(drill
				(offset 0 -0.381)
			)
			(layers "F.Cu" "F.Mask" "F.Paste")
			(net "PCIE_REFCLK_S3_P")
		)
		(pad "B77" smd rect
			(at 27.599894 -0.7747 180)
			(size 0.5588 2.3114)
			(drill
				(offset 0 -0.381)
			)
			(layers "F.Cu" "F.Mask" "F.Paste")
			(net "PCIE_REFCLK_S3_N")
		)
		(pad "B78" smd rect
			(at 28.399994 -0.7747 180)
			(size 0.5588 2.3114)
			(drill
				(offset 0 -0.381)
			)
			(layers "F.Cu" "F.Mask" "F.Paste")
			(net "GND")
		)
		(pad "B79" smd rect
			(at 29.200094 -0.7747 180)
			(size 0.5588 2.3114)
			(drill
				(offset 0 -0.381)
			)
			(layers "F.Cu" "F.Mask" "F.Paste")
			(net "BUF_I2C8_CLKBUF1_SCL")
		)
		(pad "B80" smd rect
			(at 29.99994 -0.7747 180)
			(size 0.5588 2.3114)
			(drill
				(offset 0 -0.381)
			)
			(layers "F.Cu" "F.Mask" "F.Paste")
			(net "BUF_I2C8_CLKBUF1_SDA")
		)
		(pad "B81" smd rect
			(at 30.80004 -0.7747 180)
			(size 0.5588 2.3114)
			(drill
				(offset 0 -0.381)
			)
			(layers "F.Cu" "F.Mask" "F.Paste")
			(net "GND")
		)
		(pad "B82" smd rect
			(at 31.599886 -0.7747 180)
			(size 0.5588 2.3114)
			(drill
				(offset 0 -0.381)
			)
			(layers "F.Cu" "F.Mask" "F.Paste")
			(net "SSD_PERST#5_R")
		)
		(pad "B83" smd rect
			(at 32.399986 -0.7747 180)
			(size 0.5588 2.3114)
			(drill
				(offset 0 -0.381)
			)
			(layers "F.Cu" "F.Mask" "F.Paste")
			(net "PEER_BMC_HB")
		)
		(pad "B84" smd rect
			(at 33.200086 -0.7747 180)
			(size 0.5588 2.3114)
			(drill
				(offset 0 -0.381)
			)
			(layers "F.Cu" "F.Mask" "F.Paste")
			(net "HB_OUT")
		)
		(pad "B85" smd rect
			(at 33.999932 -0.7747 180)
			(size 0.5588 2.3114)
			(drill
				(offset 0 -0.381)
			)
			(layers "F.Cu" "F.Mask" "F.Paste")
			(net "FCB_HW_REVISION")
		)
		(pad "B86" smd rect
			(at 34.800032 -0.7747 180)
			(size 0.5588 2.3114)
			(drill
				(offset 0 -0.381)
			)
			(layers "F.Cu" "F.Mask" "F.Paste")
			(net "DPB_HW_REVISION")
		)
		(pad "B87" smd rect
			(at 35.599878 -0.7747 180)
			(size 0.5588 2.3114)
			(drill
				(offset 0 -0.381)
			)
			(layers "F.Cu" "F.Mask" "F.Paste")
			(net "BMC_SELF_TRAY")
		)
		(pad "B88" smd rect
			(at 36.399978 -0.7747 180)
			(size 0.5588 2.3114)
			(drill
				(offset 0 -0.381)
			)
			(layers "F.Cu" "F.Mask" "F.Paste")
			(net "PEER_TRAY_R")
		)
		(pad "B89" smd rect
			(at 37.200078 -0.7747 180)
			(size 0.5588 2.3114)
			(drill
				(offset 0 -0.381)
			)
			(layers "F.Cu" "F.Mask" "F.Paste")
			(net "GND")
		)
		(pad "B90" smd rect
			(at 37.999924 -0.7747 180)
			(size 0.5588 2.3114)
			(drill
				(offset 0 -0.381)
			)
			(layers "F.Cu" "F.Mask" "F.Paste")
			(net "GND")
		)
		(pad "B91" smd rect
			(at 38.800024 -0.7747 180)
			(size 0.5588 2.3114)
			(drill
				(offset 0 -0.381)
			)
			(layers "F.Cu" "F.Mask" "F.Paste")
			(net "GND")
		)
		(pad "B92" smd rect
			(at 39.600124 -0.7747 180)
			(size 0.5588 2.3114)
			(drill
				(offset 0 -0.381)
			)
			(layers "F.Cu" "F.Mask" "F.Paste")
			(net "GND")
		)
		(pad "B93" smd rect
			(at 40.39997 -0.7747 180)
			(size 0.5588 2.3114)
			(drill
				(offset 0 -0.381)
			)
			(layers "F.Cu" "F.Mask" "F.Paste")
			(net "GND")
		)
		(pad "B94" smd rect
			(at 41.20007 -0.7747 180)
			(size 0.5588 2.3114)
			(drill
				(offset 0 -0.381)
			)
			(layers "F.Cu" "F.Mask" "F.Paste")
			(net "GND")
		)
		(pad "B95" smd rect
			(at 41.999916 -0.7747 180)
			(size 0.5588 2.3114)
			(drill
				(offset 0 -0.381)
			)
			(layers "F.Cu" "F.Mask" "F.Paste")
			(net "P12V_PCIE")
		)
		(pad "B96" smd rect
			(at 42.800016 -0.7747 180)
			(size 0.5588 2.3114)
			(drill
				(offset 0 -0.381)
			)
			(layers "F.Cu" "F.Mask" "F.Paste")
			(net "P12V_PCIE")
		)
		(pad "B97" smd rect
			(at 43.600116 -0.7747 180)
			(size 0.5588 2.3114)
			(drill
				(offset 0 -0.381)
			)
			(layers "F.Cu" "F.Mask" "F.Paste")
			(net "P12V_PCIE")
		)
		(pad "B98" smd rect
			(at 44.399962 -0.7747 180)
			(size 0.5588 2.3114)
			(drill
				(offset 0 -0.381)
			)
			(layers "F.Cu" "F.Mask" "F.Paste")
			(net "P12V_PCIE")
		)
		(pad "B99" smd rect
			(at 45.200062 -0.7747 180)
			(size 0.5588 2.3114)
			(drill
				(offset 0 -0.381)
			)
			(layers "F.Cu" "F.Mask" "F.Paste")
			(net "P12V_PCIE")
		)
		(pad "B100" smd rect
			(at 45.999908 -0.7747 180)
			(size 0.5588 2.3114)
			(drill
				(offset 0 -0.381)
			)
			(layers "F.Cu" "F.Mask" "F.Paste")
			(net "P12V_PCIE")
		)
	)
)
